# BASEBOARD_FAB2 (Tioga Pass) — schematic netlist excerpt (pin names and nets, part order shuffled) for the footprints in the layout excerpt that follows; sources: Cadence DE-HDL packaged netlist, KiCad conversion of Wiwynn_Tioga_Pass_MB.brd

C5G76  CAP_A  22.0UF 4V 20% X6S  pkg 0603V  page 242 : A = PVDDQ_DEF ; B = GND
C8P31  CAP  100UF 4V 20% X5R  pkg 0805  page 225 : A = PVDDQ_GHJ ; B = GND
R25W59  RES  0.0 5% CHIP  pkg 0402  page 148 : A = P3V3_STBY ; B = VCCBAT_TW12

(kicad_pcb
	(version 20260206)
	(generator "pcbnew")
	(generator_version "10.0")
	(general
		(thickness 1.6)
		(legacy_teardrops no)
	)
	(paper "A4")
	(title_block
		(title "Wiwynn_Tioga_Pass_MB.brd")
		(comment 1 "Tioga Pass / footprints 4203-4205 of 4770")
	)
	(layers
		(0 "F.Cu" signal "TOP")
		(4 "In1.Cu" signal "L2GND")
		(6 "In2.Cu" signal "L3")
		(8 "In3.Cu" signal "L4GND")
		(10 "In4.Cu" signal "L5")
		(12 "In5.Cu" signal "L6GND")
		(14 "In6.Cu" signal "L7VCC")
		(16 "In7.Cu" signal "L8VCC")
		(18 "In8.Cu" signal "L9GND")
		(20 "In9.Cu" signal "L10")
		(22 "In10.Cu" signal "L11GND")
		(24 "In11.Cu" signal "L12")
		(26 "In12.Cu" signal "L13GND")
		(2 "B.Cu" signal "BOTTOM")
		(9 "F.Adhes" user "F.Adhesive")
		(11 "B.Adhes" user "B.Adhesive")
		(13 "F.Paste" user "Package Geometry/Pastemask Top")
		(15 "B.Paste" user "Package Geometry/Pastemask Bottom")
		(5 "F.SilkS" user "Ref Des/Silkscreen Top")
		(7 "B.SilkS" user "Ref Des/Silkscreen Bottom")
		(1 "F.Mask" user "Board Geometry/Soldermask Top")
		(3 "B.Mask" user "Board Geometry/Soldermask Bottom")
		(17 "Dwgs.User" user "User.Drawings")
		(19 "Cmts.User" user "User.Comments")
		(21 "Eco1.User" user "User.Eco1")
		(23 "Eco2.User" user "User.Eco2")
		(25 "Edge.Cuts" user "Board Geometry/Outline")
		(27 "Margin" user)
		(31 "F.CrtYd" user "Package Geometry/Place Bound Top")
		(29 "B.CrtYd" user "Package Geometry/Place Bound Bottom")
		(35 "F.Fab" user "Ref Des/Assembly Top")
		(33 "B.Fab" user "Ref Des/Assembly Bottom")
	)
	(footprint ""
		(layer "B.Cu")
		(at 276.000464 -140.208 90)
		(property "Reference" "C5G76"
			(at -1.14681 0.76708 180)
			(unlocked yes)
			(layer "B.SilkS")
			(effects
				(font
					(size 0.7874 0.5842)
					(thickness 0.1524)
				)
				(justify mirror)
			)
		)
		(property "Value" ""
			(at 0 0 90)
			(layer "B.Fab")
			(effects
				(font
					(size 1.27 1.27)
				)
				(justify mirror)
			)
		)
		(duplicate_pad_numbers_are_jumpers no)
		(fp_rect
			(start -0.4953 -0.2032)
			(end 0.4953 1.6002)
			(stroke
				(width 0)
				(type default)
			)
			(fill no)
			(layer "B.CrtYd")
		)
		(fp_line
			(start 0.4953 -0.2032)
			(end -0.4953 -0.2032)
			(stroke
				(width 0.1)
				(type default)
			)
			(layer "B.Fab")
		)
		(fp_line
			(start -0.4953 -0.2032)
			(end -0.4953 1.6002)
			(stroke
				(width 0.1)
				(type default)
			)
			(layer "B.Fab")
		)
		(fp_line
			(start 0.4953 1.6002)
			(end 0.4953 -0.2032)
			(stroke
				(width 0.1)
				(type default)
			)
			(layer "B.Fab")
		)
		(fp_line
			(start -0.4953 1.6002)
			(end 0.4953 1.6002)
			(stroke
				(width 0.1)
				(type default)
			)
			(layer "B.Fab")
		)
		(pad "1" smd rect
			(at 0 0 270)
			(size 0.762 0.889)
			(layers "B.Cu" "B.Mask" "B.Paste")
			(net "PVDDQ_DEF")
		)
		(pad "2" smd rect
			(at 0 1.397 270)
			(size 0.762 0.889)
			(layers "B.Cu" "B.Mask" "B.Paste")
			(net "GND")
		)
		(zone
			(layer "B.Cu")
			(hatch none 0.5)
			(connect_pads
				(clearance 0)
			)
			(min_thickness 0.25)
			(keepout
				(tracks not_allowed)
				(vias allowed)
				(pads allowed)
				(copperpour not_allowed)
				(footprints allowed)
			)
			(placement
				(enabled no)
				(sheetname "")
			)
			(fill
				(thermal_gap 0.5)
				(thermal_bridge_width 0.5)
				(island_removal_mode 0)
			)
			(polygon
				(pts
					(xy 276.444964 -139.827) (xy 276.952964 -139.827) (xy 276.952964 -140.589) (xy 276.444964 -140.589)
				)
			)
		)
	)
	(footprint ""
		(layer "B.Cu")
		(at 101.104192 -68.184014 180)
		(property "Reference" "C8P31"
			(at 0 0 0)
			(layer "B.SilkS")
			(hide yes)
			(effects
				(font
					(size 1.27 1.27)
				)
				(justify mirror)
			)
		)
		(property "Value" ""
			(at 0 0 0)
			(layer "B.Fab")
			(effects
				(font
					(size 1.27 1.27)
				)
				(justify mirror)
			)
		)
		(duplicate_pad_numbers_are_jumpers no)
		(fp_poly
			(pts
				(xy 0.7239 -0.2159) (xy -0.7239 -0.2159) (xy -0.7239 1.9939) (xy 0.7239 1.9939)
			)
			(stroke
				(width 0)
				(type default)
			)
			(fill no)
			(layer "B.CrtYd")
		)
		(fp_line
			(start 0.7239 1.9939)
			(end -0.7239 1.9939)
			(stroke
				(width 0.1)
				(type default)
			)
			(layer "B.Fab")
		)
		(fp_line
			(start 0.7239 -0.2159)
			(end 0.7239 1.9939)
			(stroke
				(width 0.1)
				(type default)
			)
			(layer "B.Fab")
		)
		(fp_line
			(start -0.7239 1.9939)
			(end -0.7239 -0.2159)
			(stroke
				(width 0.1)
				(type default)
			)
			(layer "B.Fab")
		)
		(fp_line
			(start -0.7239 -0.2159)
			(end 0.7239 -0.2159)
			(stroke
				(width 0.1)
				(type default)
			)
			(layer "B.Fab")
		)
		(pad "1" smd rect
			(at 0 0)
			(size 1.27 1.016)
			(layers "B.Cu" "B.Mask" "B.Paste")
			(net "PVDDQ_GHJ")
		)
		(pad "2" smd rect
			(at 0 1.778)
			(size 1.27 1.016)
			(layers "B.Cu" "B.Mask" "B.Paste")
			(net "GND")
		)
		(zone
			(layer "B.Cu")
			(hatch none 0.5)
			(connect_pads
				(clearance 0)
			)
			(min_thickness 0.25)
			(keepout
				(tracks not_allowed)
				(vias allowed)
				(pads allowed)
				(copperpour not_allowed)
				(footprints allowed)
			)
			(placement
				(enabled no)
				(sheetname "")
			)
			(fill
				(thermal_gap 0.5)
				(thermal_bridge_width 0.5)
				(island_removal_mode 0)
			)
			(polygon
				(pts
					(xy 100.469192 -68.692014) (xy 101.739192 -68.692014) (xy 101.739192 -69.454014) (xy 100.469192 -69.454014)
				)
			)
		)
	)
	(footprint ""
		(layer "B.Cu")
		(at 406.654 -27.178 90)
		(property "Reference" "R25W59"
			(at 0.8382 -0.67818 90)
			(unlocked yes)
			(layer "B.SilkS")
			(effects
				(font
					(size 0.4064 0.254)
					(thickness 0.1524)
				)
				(justify left mirror)
			)
		)
		(property "Value" ""
			(at 0 0 90)
			(layer "B.Fab")
			(effects
				(font
					(size 1.27 1.27)
				)
				(justify mirror)
			)
		)
		(duplicate_pad_numbers_are_jumpers no)
		(fp_poly
			(pts
				(xy 0.2794 -0.1016) (xy -0.2794 -0.1016) (xy -0.2794 0.9906) (xy 0.2794 0.9906)
			)
			(stroke
				(width 0)
				(type default)
			)
			(fill no)
			(layer "B.CrtYd")
		)
		(fp_line
			(start 0.2794 -0.1016)
			(end 0.2794 0.9906)
			(stroke
				(width 0.1)
				(type default)
			)
			(layer "B.Fab")
		)
		(fp_line
			(start -0.2794 -0.1016)
			(end 0.2794 -0.1016)
			(stroke
				(width 0.1)
				(type default)
			)
			(layer "B.Fab")
		)
		(fp_line
			(start 0.2794 0.9906)
			(end -0.2794 0.9906)
			(stroke
				(width 0.1)
				(type default)
			)
			(layer "B.Fab")
		)
		(fp_line
			(start -0.2794 0.9906)
			(end -0.2794 -0.1016)
			(stroke
				(width 0.1)
				(type default)
			)
			(layer "B.Fab")
		)
		(pad "1" smd rect
			(at 0 0 270)
			(size 0.508 0.508)
			(layers "B.Cu" "B.Mask" "B.Paste")
			(net "P3V3_STBY")
		)
		(pad "2" smd rect
			(at 0 0.889 270)
			(size 0.508 0.508)
			(layers "B.Cu" "B.Mask" "B.Paste")
			(net "VCCBAT_TW12")
		)
		(zone
			(layer "B.Cu")
			(hatch none 0.5)
			(connect_pads
				(clearance 0)
			)
			(min_thickness 0.25)
			(keepout
				(tracks allowed)
				(vias not_allowed)
				(pads allowed)
				(copperpour not_allowed)
				(footprints allowed)
			)
			(placement
				(enabled no)
				(sheetname "")
			)
			(fill
				(thermal_gap 0.5)
				(thermal_bridge_width 0.5)
				(island_removal_mode 0)
			)
			(polygon
				(pts
					(xy 406.908 -27.432) (xy 406.908 -26.924) (xy 407.289 -26.924) (xy 407.289 -27.432)
				)
			)
		)
		(zone
			(layer "B.Cu")
			(hatch none 0.5)
			(connect_pads
				(clearance 0)
			)
			(min_thickness 0.25)
			(keepout
				(tracks not_allowed)
				(vias allowed)
				(pads allowed)
				(copperpour not_allowed)
				(footprints allowed)
			)
			(placement
				(enabled no)
				(sheetname "")
			)
			(fill
				(thermal_gap 0.5)
				(thermal_bridge_width 0.5)
				(island_removal_mode 0)
			)
			(polygon
				(pts
					(xy 407.289 -27.432) (xy 407.289 -26.924) (xy 406.908 -26.924) (xy 406.908 -27.432)
				)
			)
		)
	)
)
